#ISCELL
  mstr_misc dns *
  *
#ISCELL
  mstr_symbols cad_note *
  *
#ISCELL
  mstr_symbols design_note *
  *
#ISCELL
  mstr_symbols intel_corp_bpage *
  *
#ISCELL
  mstr_standard offpage *
  page90_i1
#ISCELL
  mstr_standard offpage *
  page90_i10
#CELL
  mstr_discrete res *
  page90_i11
#CELL
  mstr_discrete res *
  page90_i12
#ISCELL
  mstr_standard offpage *
  page90_i14
#ISCELL
  mstr_standard offpage *
  page90_i16
#CELL
  mstr_discrete res *
  page90_i17
#ISCELL
  mstr_symbols gnd *
  page90_i18
#ISCELL
  mstr_standard offpage *
  page90_i19
#ISCELL
  mstr_standard offpage *
  page90_i2
#ISCELL
  mstr_standard offpage *
  page90_i20
#ISCELL
  mstr_standard offpage *
  page90_i23
#CELL
  mstr_discrete res *
  page90_i24
#CELL
  mstr_discrete res *
  page90_i25
#CELL
  mstr_discrete res *
  page90_i28
#CELL
  mstr_discrete res *
  page90_i29
#CELL
  mstr_discrete res *
  page90_i3
#ISCELL
  mstr_symbols pvccio_cpu0 *
  page90_i30
#CELL
  mstr_discrete res *
  page90_i31
#CELL
  mstr_discrete res *
  page90_i32
#CELL
  mstr_discrete res *
  page90_i33
#CELL
  mstr_discrete res *
  page90_i4
#ISCELL
  mstr_standard offpage *
  page90_i45
#ISCELL
  mstr_standard offpage *
  page90_i46
#CELL
  mstr_discrete res *
  page90_i48
#CELL
  mstr_discrete res *
  page90_i49
#ISCELL
  mstr_symbols gnd *
  page90_i5
#ISCELL
  mstr_symbols pvccio_cpu0 *
  page90_i51
#CELL
  mstr_discrete res *
  page90_i52
#CELL
  mstr_discrete res *
  page90_i53
#ISCELL
  mstr_standard offpage *
  page90_i54
#ISCELL
  mstr_standard offpage *
  page90_i55
#ISCELL
  mstr_standard offpage *
  page90_i56
#ISCELL
  mstr_standard offpage *
  page90_i57
#CELL
  mstr_discrete res *
  page90_i59
#ISCELL
  mstr_standard offpage *
  page90_i6
#CELL
  mstr_discrete res *
  page90_i60
#ISCELL
  mstr_symbols pvccio_cpu1 *
  page90_i62
#ISCELL
  mstr_symbols pvccio_cpu1 *
  page90_i63
#ISCELL
  mstr_standard offpage *
  page90_i64
#CELL
  mstr_discrete res *
  page90_i66
#CELL
  mstr_discrete res *
  page90_i68
#ISCELL
  mstr_standard offpage *
  page90_i69
#ISCELL
  mstr_standard offpage *
  page90_i7
#CELL
  mstr_discrete res *
  page90_i70
#ISCELL
  mstr_standard offpage *
  page90_i71
#CELL
  mstr_discrete res *
  page90_i72
#ISCELL
  mstr_standard offpage *
  page90_i73
#CELL
  mstr_discrete res *
  page90_i74
#ISCELL
  mstr_standard offpage *
  page90_i75
#CELL
  mstr_discrete res *
  page90_i76
#ISCELL
  mstr_standard offpage *
  page90_i77
#ISCELL
  mstr_symbols gnd *
  page90_i78
#CELL
  mstr_discrete res *
  page90_i79
#ISCELL
  mstr_standard offpage *
  page90_i8
#CELL
  mstr_discrete res *
  page90_i80
#CELL
  mstr_discrete res *
  page90_i81
#ISCELL
  mstr_standard offpage *
  page90_i82
#ISCELL
  mstr_standard offpage *
  page90_i83
#ISCELL
  mstr_standard offpage *
  page90_i84
#CELL
  mstr_discrete res *
  page90_i85
#CELL
  mstr_discrete res *
  page90_i86
#ISCELL
  mstr_symbols gnd *
  page90_i87
#CELL
  mstr_discrete res *
  page90_i88
#ISCELL
  mstr_standard offpage *
  page90_i89
#ISCELL
  mstr_standard offpage *
  page90_i9
#ISCELL
  mstr_standard offpage *
  page90_i90
#ISCELL
  mstr_standard offpage *
  page90_i91
